# T6G (Grand Teton) — schematic netlist excerpt (pin names and nets, part order shuffled) for the footprints in the layout excerpt that follows; sources: Cadence DE-HDL packaged netlist, KiCad conversion of 04192023_DAF0TMB3IC0_F0TG_MB_C_brd_V02_OCP.brd

U242  74LVC2G08DP  EMPTY  pkg TSSOP8_0-65_3X3  page 143
  \1a\  = OCP_SFF_PRSNT01_R1_N
  \1b\  = OCP_SFF_PRSNT23_R1_N
  \2y\  = OCP_V3_2_PRSNT_ALL_R_N
  GND  = GND
  \2a\  = OCP_V3_2_PRSNT01_R1_N
  \2b\  = OCP_V3_2_PRSNT23_R1_N
  \1y\  = OCP_SFF_PRSNT_ALL_R_N
  VCC  = P3V3_AUX

PC2216  Q_CAP  6800PF 50V 10% X7R  pkg C0402  page 146 : A = P3V3_E1S_GATE_0 ; B = GND

(kicad_pcb
	(version 20260206)
	(generator "pcbnew")
	(generator_version "10.0")
	(general
		(thickness 1.6)
		(legacy_teardrops no)
	)
	(paper "A4")
	(title_block
		(title "04192023_DAF0TMB3IC0_F0TG_MB_C_brd_V02_OCP.brd")
		(comment 1 "Grand Teton / footprints 948-949 of 8354")
	)
	(layers
		(0 "F.Cu" signal "TOP")
		(4 "In1.Cu" signal "GND")
		(6 "In2.Cu" signal "IN1")
		(8 "In3.Cu" signal "GND1")
		(10 "In4.Cu" signal "IN2")
		(12 "In5.Cu" signal "GND2")
		(14 "In6.Cu" signal "IN3")
		(16 "In7.Cu" signal "GND3")
		(18 "In8.Cu" signal "VCC")
		(20 "In9.Cu" signal "VCC1")
		(22 "In10.Cu" signal "GND4")
		(24 "In11.Cu" signal "IN4")
		(26 "In12.Cu" signal "GND5")
		(28 "In13.Cu" signal "IN5")
		(30 "In14.Cu" signal "GND6")
		(32 "In15.Cu" signal "IN6")
		(34 "In16.Cu" signal "GND7")
		(2 "B.Cu" signal "BOTTOM")
		(9 "F.Adhes" user "F.Adhesive")
		(11 "B.Adhes" user "B.Adhesive")
		(13 "F.Paste" user "Package Geometry/Pastemask Top")
		(15 "B.Paste" user "Package Geometry/Pastemask Bottom")
		(5 "F.SilkS" user "Ref Des/Silkscreen Top")
		(7 "B.SilkS" user "Ref Des/Silkscreen Bottom")
		(1 "F.Mask" user "Board Geometry/Soldermask Top")
		(3 "B.Mask" user "Board Geometry/Soldermask Bottom")
		(17 "Dwgs.User" user "User.Drawings")
		(19 "Cmts.User" user "User.Comments")
		(21 "Eco1.User" user "User.Eco1")
		(23 "Eco2.User" user "User.Eco2")
		(25 "Edge.Cuts" user "Board Geometry/Outline")
		(27 "Margin" user)
		(31 "F.CrtYd" user "Package Geometry/Place Bound Top")
		(29 "B.CrtYd" user "Package Geometry/Place Bound Bottom")
		(35 "F.Fab" user "Ref Des/Assembly Top")
		(33 "B.Fab" user "Ref Des/Assembly Bottom")
	)
	(footprint ""
		(layer "F.Cu")
		(at 223.37141 -73.517506)
		(property "Reference" "PC2216"
			(at 0 0 0)
			(layer "F.SilkS")
			(hide yes)
			(effects
				(font
					(size 1.27 1.27)
				)
			)
		)
		(property "Value" ""
			(at 0 0 0)
			(layer "F.Fab")
			(effects
				(font
					(size 1.27 1.27)
				)
			)
		)
		(duplicate_pad_numbers_are_jumpers no)
		(fp_line
			(start -0.7874 -0.4064)
			(end 0.7874 -0.4064)
			(stroke
				(width 0.1524)
				(type default)
			)
			(layer "F.SilkS")
		)
		(fp_line
			(start -0.7874 0.4064)
			(end -0.7874 -0.4064)
			(stroke
				(width 0.1524)
				(type default)
			)
			(layer "F.SilkS")
		)
		(fp_line
			(start 0.7874 -0.4064)
			(end 0.7874 0.4064)
			(stroke
				(width 0.1524)
				(type default)
			)
			(layer "F.SilkS")
		)
		(fp_line
			(start 0.7874 0.4064)
			(end -0.7874 0.4064)
			(stroke
				(width 0.1524)
				(type default)
			)
			(layer "F.SilkS")
		)
		(fp_line
			(start -0.67945 -0.305054)
			(end -0.12065 -0.305054)
			(stroke
				(width 0.1)
				(type default)
			)
			(layer "F.Fab")
		)
		(fp_line
			(start -0.67945 0.3048)
			(end -0.67945 -0.305054)
			(stroke
				(width 0.1)
				(type default)
			)
			(layer "F.Fab")
		)
		(fp_line
			(start -0.12065 -0.305054)
			(end -0.12065 -0.2794)
			(stroke
				(width 0.1)
				(type default)
			)
			(layer "F.Fab")
		)
		(fp_line
			(start -0.12065 -0.2794)
			(end 0.12065 -0.2794)
			(stroke
				(width 0.1)
				(type default)
			)
			(layer "F.Fab")
		)
		(fp_line
			(start -0.12065 0.2794)
			(end -0.12065 0.3048)
			(stroke
				(width 0.1)
				(type default)
			)
			(layer "F.Fab")
		)
		(fp_line
			(start -0.12065 0.3048)
			(end -0.67945 0.3048)
			(stroke
				(width 0.1)
				(type default)
			)
			(layer "F.Fab")
		)
		(fp_line
			(start 0.120396 0.2794)
			(end -0.12065 0.2794)
			(stroke
				(width 0.1)
				(type default)
			)
			(layer "F.Fab")
		)
		(fp_line
			(start 0.120396 0.3048)
			(end 0.120396 0.2794)
			(stroke
				(width 0.1)
				(type default)
			)
			(layer "F.Fab")
		)
		(fp_line
			(start 0.12065 -0.3048)
			(end 0.67945 -0.3048)
			(stroke
				(width 0.1)
				(type default)
			)
			(layer "F.Fab")
		)
		(fp_line
			(start 0.12065 -0.2794)
			(end 0.12065 -0.3048)
			(stroke
				(width 0.1)
				(type default)
			)
			(layer "F.Fab")
		)
		(fp_line
			(start 0.67945 -0.3048)
			(end 0.67945 0.3048)
			(stroke
				(width 0.1)
				(type default)
			)
			(layer "F.Fab")
		)
		(fp_line
			(start 0.67945 0.3048)
			(end 0.120396 0.3048)
			(stroke
				(width 0.1)
				(type default)
			)
			(layer "F.Fab")
		)
		(pad "1" smd circle
			(at -0.40005 0)
			(size 0 0)
			(layers "F.Cu" "F.Mask" "F.Paste")
			(net "P3V3_E1S_GATE_0")
		)
		(pad "2" smd circle
			(at 0.40005 0)
			(size 0 0)
			(layers "F.Cu" "F.Mask" "F.Paste")
			(net "GND")
		)
	)
	(footprint ""
		(layer "F.Cu")
		(at 13.12672 -74.719688)
		(property "Reference" "U242"
			(at 1.629156 2.268982 0)
			(unlocked yes)
			(layer "F.SilkS")
			(effects
				(font
					(size 0.7874 0.5842)
					(thickness 0.1524)
				)
				(justify left)
			)
		)
		(property "Value" ""
			(at 0 0 0)
			(layer "F.Fab")
			(effects
				(font
					(size 1.27 1.27)
				)
			)
		)
		(duplicate_pad_numbers_are_jumpers no)
		(fp_line
			(start -1.207008 -1.549908)
			(end -1.207008 1.549908)
			(stroke
				(width 0.1524)
				(type default)
			)
			(layer "F.SilkS")
		)
		(fp_line
			(start -1.207008 1.549908)
			(end 1.207008 1.549908)
			(stroke
				(width 0.1524)
				(type default)
			)
			(layer "F.SilkS")
		)
		(fp_line
			(start -0.762508 -1.549908)
			(end -1.207008 -1.549908)
			(stroke
				(width 0.1524)
				(type default)
			)
			(layer "F.SilkS")
		)
		(fp_line
			(start 0 -0.635)
			(end -0.762508 -1.549908)
			(stroke
				(width 0.1524)
				(type default)
			)
			(layer "F.SilkS")
		)
		(fp_line
			(start 0.762508 -1.549908)
			(end 0 -0.635)
			(stroke
				(width 0.1524)
				(type default)
			)
			(layer "F.SilkS")
		)
		(fp_line
			(start 1.207008 -1.549908)
			(end 0.762508 -1.549908)
			(stroke
				(width 0.1524)
				(type default)
			)
			(layer "F.SilkS")
		)
		(fp_line
			(start 1.207008 1.549908)
			(end 1.207008 -1.549908)
			(stroke
				(width 0.1524)
				(type default)
			)
			(layer "F.SilkS")
		)
		(fp_poly
			(pts
				(xy -2.608326 -0.655828) (xy -3.524758 0.015494) (xy -3.695192 -0.986028)
			)
			(stroke
				(width 0)
				(type default)
			)
			(fill yes)
			(layer "F.SilkS")
		)
		(fp_line
			(start -1.549908 -1.549908)
			(end -1.549908 1.549908)
			(stroke
				(width 0.1)
				(type default)
			)
			(layer "F.Fab")
		)
		(fp_line
			(start -1.549908 1.549908)
			(end 1.549908 1.549908)
			(stroke
				(width 0.1)
				(type default)
			)
			(layer "F.Fab")
		)
		(fp_line
			(start 1.549908 -1.549908)
			(end -1.549908 -1.549908)
			(stroke
				(width 0.1)
				(type default)
			)
			(layer "F.Fab")
		)
		(fp_line
			(start 1.549908 1.549908)
			(end 1.549908 -1.549908)
			(stroke
				(width 0.1)
				(type default)
			)
			(layer "F.Fab")
		)
		(fp_poly
			(pts
				(xy -3.4036 -1.53289) (xy -3.4036 -0.51689) (xy -2.3876 -1.02489)
			)
			(stroke
				(width 0)
				(type default)
			)
			(fill yes)
			(layer "F.Fab")
		)
		(pad "1" smd rect
			(at -1.774952 -1.02489 270)
			(size 0.508 0.8636)
			(layers "F.Cu" "F.Mask" "F.Paste")
			(net "OCP_SFF_PRSNT01_R1_N")
		)
		(pad "2" smd rect
			(at -1.774952 -0.32512 270)
			(size 0.4064 0.8636)
			(layers "F.Cu" "F.Mask" "F.Paste")
			(net "OCP_SFF_PRSNT23_R1_N")
		)
		(pad "3" smd rect
			(at -1.774952 0.32512 270)
			(size 0.4064 0.8636)
			(layers "F.Cu" "F.Mask" "F.Paste")
			(net "OCP_V3_2_PRSNT_ALL_R_N")
		)
		(pad "4" smd rect
			(at -1.774952 1.02489 270)
			(size 0.508 0.8636)
			(layers "F.Cu" "F.Mask" "F.Paste")
			(net "GND")
		)
		(pad "5" smd rect
			(at 1.774952 1.02489 270)
			(size 0.508 0.8636)
			(layers "F.Cu" "F.Mask" "F.Paste")
			(net "OCP_V3_2_PRSNT01_R1_N")
		)
		(pad "6" smd rect
			(at 1.774952 0.32512 270)
			(size 0.4064 0.8636)
			(layers "F.Cu" "F.Mask" "F.Paste")
			(net "OCP_V3_2_PRSNT23_R1_N")
		)
		(pad "7" smd rect
			(at 1.774952 -0.32512 270)
			(size 0.4064 0.8636)
			(layers "F.Cu" "F.Mask" "F.Paste")
			(net "OCP_SFF_PRSNT_ALL_R_N")
		)
		(pad "8" smd rect
			(at 1.774952 -1.02489 270)
			(size 0.508 0.8636)
			(layers "F.Cu" "F.Mask" "F.Paste")
			(net "P3V3_AUX")
		)
	)
)
